# T6G (Grand Teton) — schematic netlist excerpt (pin names and nets, part order shuffled) for the footprints in the layout excerpt that follows; sources: Cadence DE-HDL packaged netlist, KiCad conversion of 04192023_DAF0TMB3IC0_F0TG_MB_C_brd_V02_OCP.brd

PJ09_P0_N  Q_SHORT  EMPTY  pkg SM  page 362 : \1\ = GND ; \2\ = P0V9_RETIMER_CPU0_SENSE_SH_N
C2342  Q_CAP  22UF 4V 20% X6S  pkg C0402  page 73 : A = PVDDCR_CPU0_P1 ; B = GND
PR6802  Q_RES  0 5% EMPTY  pkg 0402LF  page 364 : A = TP_P0V9_RETIMER_CPU1_SVID_ALERT_N ; B = GND

(kicad_pcb
	(version 20260206)
	(generator "pcbnew")
	(generator_version "10.0")
	(general
		(thickness 1.6)
		(legacy_teardrops no)
	)
	(paper "A4")
	(title_block
		(title "04192023_DAF0TMB3IC0_F0TG_MB_C_brd_V02_OCP.brd")
		(comment 1 "Grand Teton / footprints 5920-5922 of 8354")
	)
	(layers
		(0 "F.Cu" signal "TOP")
		(4 "In1.Cu" signal "GND")
		(6 "In2.Cu" signal "IN1")
		(8 "In3.Cu" signal "GND1")
		(10 "In4.Cu" signal "IN2")
		(12 "In5.Cu" signal "GND2")
		(14 "In6.Cu" signal "IN3")
		(16 "In7.Cu" signal "GND3")
		(18 "In8.Cu" signal "VCC")
		(20 "In9.Cu" signal "VCC1")
		(22 "In10.Cu" signal "GND4")
		(24 "In11.Cu" signal "IN4")
		(26 "In12.Cu" signal "GND5")
		(28 "In13.Cu" signal "IN5")
		(30 "In14.Cu" signal "GND6")
		(32 "In15.Cu" signal "IN6")
		(34 "In16.Cu" signal "GND7")
		(2 "B.Cu" signal "BOTTOM")
		(9 "F.Adhes" user "F.Adhesive")
		(11 "B.Adhes" user "B.Adhesive")
		(13 "F.Paste" user "Package Geometry/Pastemask Top")
		(15 "B.Paste" user "Package Geometry/Pastemask Bottom")
		(5 "F.SilkS" user "Ref Des/Silkscreen Top")
		(7 "B.SilkS" user "Ref Des/Silkscreen Bottom")
		(1 "F.Mask" user "Board Geometry/Soldermask Top")
		(3 "B.Mask" user "Board Geometry/Soldermask Bottom")
		(17 "Dwgs.User" user "User.Drawings")
		(19 "Cmts.User" user "User.Comments")
		(21 "Eco1.User" user "User.Eco1")
		(23 "Eco2.User" user "User.Eco2")
		(25 "Edge.Cuts" user "Board Geometry/Outline")
		(27 "Margin" user)
		(31 "F.CrtYd" user "Package Geometry/Place Bound Top")
		(29 "B.CrtYd" user "Package Geometry/Place Bound Bottom")
		(35 "F.Fab" user "Ref Des/Assembly Top")
		(33 "B.Fab" user "Ref Des/Assembly Bottom")
	)
	(footprint ""
		(layer "B.Cu")
		(at 113.451386 -246.447564 -60)
		(property "Reference" "C2342"
			(at 0 0 120)
			(layer "B.SilkS")
			(hide yes)
			(effects
				(font
					(size 1.27 1.27)
				)
				(justify mirror)
			)
		)
		(property "Value" ""
			(at 0 0 120)
			(layer "B.Fab")
			(effects
				(font
					(size 1.27 1.27)
				)
				(justify mirror)
			)
		)
		(duplicate_pad_numbers_are_jumpers no)
		(fp_line
			(start -0.787516 0.406438)
			(end 0.787425 0.40652)
			(stroke
				(width 0.1524)
				(type default)
			)
			(layer "B.SilkS")
		)
		(fp_line
			(start -0.787425 -0.40652)
			(end -0.787516 0.406438)
			(stroke
				(width 0.1524)
				(type default)
			)
			(layer "B.SilkS")
		)
		(fp_line
			(start 0.787425 0.40652)
			(end 0.787516 -0.406438)
			(stroke
				(width 0.1524)
				(type default)
			)
			(layer "B.SilkS")
		)
		(fp_line
			(start 0.787516 -0.406438)
			(end -0.787425 -0.40652)
			(stroke
				(width 0.1524)
				(type default)
			)
			(layer "B.SilkS")
		)
		(fp_line
			(start -0.679568 0.304811)
			(end -0.120258 0.304812)
			(stroke
				(width 0.1)
				(type default)
			)
			(layer "B.Fab")
		)
		(fp_line
			(start -0.120258 0.304812)
			(end -0.120334 0.279545)
			(stroke
				(width 0.1)
				(type default)
			)
			(layer "B.Fab")
		)
		(fp_line
			(start -0.120334 0.279545)
			(end 0.120587 0.279326)
			(stroke
				(width 0.1)
				(type default)
			)
			(layer "B.Fab")
		)
		(fp_line
			(start 0.120536 0.304813)
			(end 0.6795 0.304908)
			(stroke
				(width 0.1)
				(type default)
			)
			(layer "B.Fab")
		)
		(fp_line
			(start 0.120587 0.279326)
			(end 0.120536 0.304813)
			(stroke
				(width 0.1)
				(type default)
			)
			(layer "B.Fab")
		)
		(fp_line
			(start -0.6795 -0.304908)
			(end -0.679568 0.304811)
			(stroke
				(width 0.1)
				(type default)
			)
			(layer "B.Fab")
		)
		(fp_line
			(start 0.6795 0.304908)
			(end 0.679475 -0.305158)
			(stroke
				(width 0.1)
				(type default)
			)
			(layer "B.Fab")
		)
		(fp_line
			(start -0.120587 -0.279326)
			(end -0.120536 -0.304813)
			(stroke
				(width 0.1)
				(type default)
			)
			(layer "B.Fab")
		)
		(fp_line
			(start -0.120536 -0.304813)
			(end -0.6795 -0.304908)
			(stroke
				(width 0.1)
				(type default)
			)
			(layer "B.Fab")
		)
		(fp_line
			(start 0.120554 -0.279418)
			(end -0.120587 -0.279326)
			(stroke
				(width 0.1)
				(type default)
			)
			(layer "B.Fab")
		)
		(fp_line
			(start 0.120732 -0.305125)
			(end 0.120554 -0.279418)
			(stroke
				(width 0.1)
				(type default)
			)
			(layer "B.Fab")
		)
		(fp_line
			(start 0.679475 -0.305158)
			(end 0.120732 -0.305125)
			(stroke
				(width 0.1)
				(type default)
			)
			(layer "B.Fab")
		)
		(pad "1" smd circle
			(at 0.40005 0 120)
			(size 0 0)
			(layers "B.Cu" "B.Mask" "B.Paste")
			(net "PVDDCR_CPU0_P1")
		)
		(pad "2" smd circle
			(at -0.40005 0 120)
			(size 0 0)
			(layers "B.Cu" "B.Mask" "B.Paste")
			(net "GND")
		)
	)
	(footprint ""
		(layer "B.Cu")
		(at 20.480782 -412.850584 180)
		(property "Reference" "PR6802"
			(at 0 0 0)
			(layer "B.SilkS")
			(hide yes)
			(effects
				(font
					(size 1.27 1.27)
				)
				(justify mirror)
			)
		)
		(property "Value" ""
			(at 0 0 0)
			(layer "B.Fab")
			(effects
				(font
					(size 1.27 1.27)
				)
				(justify mirror)
			)
		)
		(duplicate_pad_numbers_are_jumpers no)
		(fp_line
			(start 0.7874 0.4064)
			(end 0.7874 -0.4064)
			(stroke
				(width 0.1524)
				(type default)
			)
			(layer "B.SilkS")
		)
		(fp_line
			(start 0.7874 -0.4064)
			(end -0.7874 -0.4064)
			(stroke
				(width 0.1524)
				(type default)
			)
			(layer "B.SilkS")
		)
		(fp_line
			(start -0.7874 0.4064)
			(end 0.7874 0.4064)
			(stroke
				(width 0.1524)
				(type default)
			)
			(layer "B.SilkS")
		)
		(fp_line
			(start -0.7874 -0.4064)
			(end -0.7874 0.4064)
			(stroke
				(width 0.1524)
				(type default)
			)
			(layer "B.SilkS")
		)
		(fp_line
			(start 0.67945 0.3048)
			(end 0.67945 -0.305054)
			(stroke
				(width 0.1)
				(type default)
			)
			(layer "B.Fab")
		)
		(fp_line
			(start 0.67945 -0.305054)
			(end 0.12065 -0.305054)
			(stroke
				(width 0.1)
				(type default)
			)
			(layer "B.Fab")
		)
		(fp_line
			(start 0.12065 0.3048)
			(end 0.67945 0.3048)
			(stroke
				(width 0.1)
				(type default)
			)
			(layer "B.Fab")
		)
		(fp_line
			(start 0.12065 0.2794)
			(end 0.12065 0.3048)
			(stroke
				(width 0.1)
				(type default)
			)
			(layer "B.Fab")
		)
		(fp_line
			(start 0.12065 -0.2794)
			(end -0.12065 -0.2794)
			(stroke
				(width 0.1)
				(type default)
			)
			(layer "B.Fab")
		)
		(fp_line
			(start 0.12065 -0.305054)
			(end 0.12065 -0.2794)
			(stroke
				(width 0.1)
				(type default)
			)
			(layer "B.Fab")
		)
		(fp_line
			(start -0.120396 0.3048)
			(end -0.120396 0.2794)
			(stroke
				(width 0.1)
				(type default)
			)
			(layer "B.Fab")
		)
		(fp_line
			(start -0.120396 0.2794)
			(end 0.12065 0.2794)
			(stroke
				(width 0.1)
				(type default)
			)
			(layer "B.Fab")
		)
		(fp_line
			(start -0.12065 -0.2794)
			(end -0.12065 -0.3048)
			(stroke
				(width 0.1)
				(type default)
			)
			(layer "B.Fab")
		)
		(fp_line
			(start -0.12065 -0.3048)
			(end -0.67945 -0.3048)
			(stroke
				(width 0.1)
				(type default)
			)
			(layer "B.Fab")
		)
		(fp_line
			(start -0.67945 0.3048)
			(end -0.120396 0.3048)
			(stroke
				(width 0.1)
				(type default)
			)
			(layer "B.Fab")
		)
		(fp_line
			(start -0.67945 -0.3048)
			(end -0.67945 0.3048)
			(stroke
				(width 0.1)
				(type default)
			)
			(layer "B.Fab")
		)
		(pad "1" smd circle
			(at 0.40005 0)
			(size 0 0)
			(layers "B.Cu" "B.Mask" "B.Paste")
			(net "TP_P0V9_RETIMER_CPU1_SVID_ALERT_N")
		)
		(pad "2" smd circle
			(at -0.40005 0)
			(size 0 0)
			(layers "B.Cu" "B.Mask" "B.Paste")
			(net "GND")
		)
	)
	(footprint ""
		(layer "B.Cu")
		(at 304.436018 -409.560014 90)
		(property "Reference" "PJ09_P0_N"
			(at 0 0 90)
			(layer "B.SilkS")
			(hide yes)
			(effects
				(font
					(size 1.27 1.27)
				)
				(justify mirror)
			)
		)
		(property "Value" ""
			(at 0 0 90)
			(layer "B.Fab")
			(effects
				(font
					(size 1.27 1.27)
				)
				(justify mirror)
			)
		)
		(duplicate_pad_numbers_are_jumpers no)
		(zone
			(layer "In11.Cu")
			(hatch none 0.5)
			(connect_pads
				(clearance 0)
			)
			(min_thickness 0.25)
			(keepout
				(tracks allowed)
				(vias not_allowed)
				(pads allowed)
				(copperpour not_allowed)
				(footprints allowed)
			)
			(placement
				(enabled no)
				(sheetname "")
			)
			(fill
				(thermal_gap 0.5)
				(thermal_bridge_width 0.5)
				(island_removal_mode 0)
			)
			(polygon
				(pts
					(xy 304.626518 -409.775914) (xy 304.626518 -409.344114) (xy 304.245518 -409.344114) (xy 304.245518 -409.775914)
				)
			)
		)
	)
)
